(kicad_pcb
	(version 20260206)
	(generator "pcbnew")
	(generator_version "10.0")
	(general
		(thickness 1.6)
		(legacy_teardrops no)
	)
	(paper "A4")
	(title_block
		(title "fcb — 12433-1M.1206WZS1330.brd")
		(comment 1 "Open Vault / Knox (Wiwynn) / footprints 132-138 of 495")
	)
	(layers
		(0 "F.Cu" signal "TOP")
		(4 "In1.Cu" signal "L2GND")
		(6 "In2.Cu" signal "L3VCC")
		(2 "B.Cu" signal "BOTTOM")
		(9 "F.Adhes" user "F.Adhesive")
		(11 "B.Adhes" user "B.Adhesive")
		(13 "F.Paste" user "Package Geometry/Pastemask Top")
		(15 "B.Paste" user "Package Geometry/Pastemask Bottom")
		(5 "F.SilkS" user "Ref Des/Silkscreen Top")
		(7 "B.SilkS" user "Ref Des/Silkscreen Bottom")
		(1 "F.Mask" user "Board Geometry/Soldermask Top")
		(3 "B.Mask" user "Board Geometry/Soldermask Bottom")
		(17 "Dwgs.User" user "User.Drawings")
		(19 "Cmts.User" user "User.Comments")
		(21 "Eco1.User" user "User.Eco1")
		(23 "Eco2.User" user "User.Eco2")
		(25 "Edge.Cuts" user "Board Geometry/Outline")
		(27 "Margin" user)
		(31 "F.CrtYd" user "Package Geometry/Place Bound Top")
		(29 "B.CrtYd" user "Package Geometry/Place Bound Bottom")
		(35 "F.Fab" user "Ref Des/Assembly Top")
		(33 "B.Fab" user "Ref Des/Assembly Bottom")
	)
	(footprint ""
		(layer "F.Cu")
		(at 37.338 -184.531 180)
		(property "Reference" "PC1262"
			(at 0 0 180)
			(layer "F.SilkS")
			(hide yes)
			(effects
				(font
					(size 1.27 1.27)
				)
			)
		)
		(property "Value" "SC10U16V6KX-2GP"
			(at -0.0762 -5.1308 180)
			(unlocked yes)
			(layer "F.Fab")
			(hide yes)
			(effects
				(font
					(size 1.016 1.016)
					(thickness 0.1524)
				)
			)
		)
		(property "Device Type" "C1206H71"
			(at -0.127 -6.6548 180)
			(unlocked yes)
			(layer "F.Fab")
			(hide yes)
			(effects
				(font
					(size 1.016 1.016)
					(thickness 0.1524)
				)
			)
		)
		(duplicate_pad_numbers_are_jumpers no)
		(fp_line
			(start 1.016 2.2352)
			(end -1.016 2.2352)
			(stroke
				(width 0.1524)
				(type default)
			)
			(layer "F.SilkS")
		)
		(fp_line
			(start 1.016 0.8382)
			(end 1.016 2.2352)
			(stroke
				(width 0.1524)
				(type default)
			)
			(layer "F.SilkS")
		)
		(fp_line
			(start 1.016 -2.2352)
			(end 1.016 -0.8382)
			(stroke
				(width 0.1524)
				(type default)
			)
			(layer "F.SilkS")
		)
		(fp_line
			(start -1.016 2.2352)
			(end -1.016 0.8382)
			(stroke
				(width 0.1524)
				(type default)
			)
			(layer "F.SilkS")
		)
		(fp_line
			(start -1.016 -0.8382)
			(end -1.016 -2.2352)
			(stroke
				(width 0.1524)
				(type default)
			)
			(layer "F.SilkS")
		)
		(fp_line
			(start -1.016 -2.2352)
			(end 1.016 -2.2352)
			(stroke
				(width 0.1524)
				(type default)
			)
			(layer "F.SilkS")
		)
		(fp_rect
			(start -1.0922 2.3114)
			(end 1.0922 -2.3114)
			(stroke
				(width 0)
				(type default)
			)
			(fill no)
			(layer "F.CrtYd")
		)
		(fp_poly
			(pts
				(xy 1.0922 -2.3114) (xy 1.0922 2.3114) (xy -1.0922 2.3114) (xy -1.0922 -2.3114)
			)
			(stroke
				(width 0)
				(type default)
			)
			(fill no)
			(layer "F.Fab")
		)
		(pad "1" smd rect
			(at 0 -1.397 180)
			(size 1.651 1.27)
			(layers "F.Cu" "F.Mask" "F.Paste")
			(net "P3V3_AUX")
		)
		(pad "2" smd rect
			(at 0 1.397 180)
			(size 1.651 1.27)
			(layers "F.Cu" "F.Mask" "F.Paste")
			(net "GND")
		)
	)
	(footprint ""
		(layer "F.Cu")
		(at 36.1442 -374.9802 180)
		(property "Reference" "PD1"
			(at 0 0 180)
			(layer "F.SilkS")
			(hide yes)
			(effects
				(font
					(size 1.27 1.27)
				)
			)
		)
		(property "Value" "MM3Z15VT1G-GP"
			(at 0 -6.7818 180)
			(unlocked yes)
			(layer "F.Fab")
			(hide yes)
			(effects
				(font
					(size 1.016 1.016)
					(thickness 0.1524)
				)
			)
		)
		(property "Device Type" "SOD323AKH44"
			(at 0 -8.6868 180)
			(unlocked yes)
			(layer "F.Fab")
			(hide yes)
			(effects
				(font
					(size 1.016 1.016)
					(thickness 0.1524)
				)
			)
		)
		(duplicate_pad_numbers_are_jumpers no)
		(fp_line
			(start 0.889 2.159)
			(end -0.889 2.159)
			(stroke
				(width 0.1524)
				(type default)
			)
			(layer "F.SilkS")
		)
		(fp_line
			(start 0.889 -1.9304)
			(end 0.889 2.159)
			(stroke
				(width 0.1524)
				(type default)
			)
			(layer "F.SilkS")
		)
		(fp_line
			(start 0.762 2.0574)
			(end -0.762 2.0574)
			(stroke
				(width 0.508)
				(type default)
			)
			(layer "F.SilkS")
		)
		(fp_line
			(start -0.889 2.159)
			(end -0.889 -1.9304)
			(stroke
				(width 0.1524)
				(type default)
			)
			(layer "F.SilkS")
		)
		(fp_line
			(start -0.889 -1.9304)
			(end 0.889 -1.9304)
			(stroke
				(width 0.1524)
				(type default)
			)
			(layer "F.SilkS")
		)
		(fp_rect
			(start -1.016 2.3114)
			(end 1.016 -2.0066)
			(stroke
				(width 0)
				(type default)
			)
			(fill no)
			(layer "F.CrtYd")
		)
		(fp_poly
			(pts
				(xy -1.016 -2.0066) (xy 1.016 -2.0066) (xy 1.016 2.3114) (xy -1.016 2.3114)
			)
			(stroke
				(width 0)
				(type default)
			)
			(fill no)
			(layer "F.Fab")
		)
		(pad "A" smd rect
			(at 0 -1.143 180)
			(size 0.5588 1.016)
			(layers "F.Cu" "F.Mask" "F.Paste")
			(net "ADM1276_GATE_RSV")
		)
		(pad "K" smd rect
			(at 0 1.143 180)
			(size 0.5588 1.016)
			(layers "F.Cu" "F.Mask" "F.Paste")
			(net "ADM1276_GATE")
		)
	)
	(footprint ""
		(layer "F.Cu")
		(at 11.811 -426.847 90)
		(property "Reference" "PD2"
			(at 0 0 90)
			(layer "F.SilkS")
			(hide yes)
			(effects
				(font
					(size 1.27 1.27)
				)
			)
		)
		(property "Value" "SMCJ15A-1-GP"
			(at -4.7244 1.5748 90)
			(unlocked yes)
			(layer "F.Fab")
			(hide yes)
			(effects
				(font
					(size 1.016 1.016)
					(thickness 0.1524)
				)
			)
		)
		(property "Device Type" "TVS794591-114297H104"
			(at -4.7244 0.0508 90)
			(unlocked yes)
			(layer "F.Fab")
			(hide yes)
			(effects
				(font
					(size 1.016 1.016)
					(thickness 0.1524)
				)
			)
		)
		(duplicate_pad_numbers_are_jumpers no)
		(fp_line
			(start 3.2004 -4.8641)
			(end -3.2004 -4.8641)
			(stroke
				(width 0.1524)
				(type default)
			)
			(layer "F.SilkS")
		)
		(fp_line
			(start -3.2004 -4.8641)
			(end -3.2004 4.8641)
			(stroke
				(width 0.1524)
				(type default)
			)
			(layer "F.SilkS")
		)
		(fp_line
			(start 3.2004 4.8641)
			(end 3.2004 -4.8641)
			(stroke
				(width 0.1524)
				(type default)
			)
			(layer "F.SilkS")
		)
		(fp_line
			(start -3.2004 4.8641)
			(end 3.2004 4.8641)
			(stroke
				(width 0.1524)
				(type default)
			)
			(layer "F.SilkS")
		)
		(fp_line
			(start 3.2004 5.0419)
			(end -3.2004 5.0419)
			(stroke
				(width 0.508)
				(type default)
			)
			(layer "F.SilkS")
		)
		(fp_rect
			(start -2.9464 3.9751)
			(end 2.9464 -3.9751)
			(stroke
				(width 0)
				(type default)
			)
			(fill no)
			(layer "F.CrtYd")
		)
		(fp_poly
			(pts
				(xy -3.4544 4.9403) (xy -3.4544 -4.9403) (xy 3.4544 -4.9403) (xy 3.4544 3.9624) (xy 2.9464 3.9624)
				(xy 2.9464 -3.9751) (xy -2.9464 -3.9751) (xy -2.9464 3.9751) (xy 3.4544 3.9751) (xy 3.4544 4.9403)
			)
			(stroke
				(width 0)
				(type default)
			)
			(fill no)
			(layer "F.CrtYd")
		)
		(fp_rect
			(start -3.4544 4.9403)
			(end 3.4544 -4.9403)
			(stroke
				(width 0)
				(type default)
			)
			(fill no)
			(layer "F.Fab")
		)
		(pad "A" smd rect
			(at 0 -3.591814 90)
			(size 3.2258 2.032)
			(layers "F.Cu" "F.Mask" "F.Paste")
			(net "GND")
		)
		(pad "K" smd rect
			(at 0 3.591814 90)
			(size 3.2258 2.032)
			(layers "F.Cu" "F.Mask" "F.Paste")
			(net "P12V_AUX")
		)
	)
	(footprint ""
		(layer "F.Cu")
		(at 41.91 -350.647 90)
		(property "Reference" "JP1"
			(at 0 0 90)
			(layer "F.SilkS")
			(hide yes)
			(effects
				(font
					(size 1.27 1.27)
				)
			)
		)
		(property "Value" "PIN-CON3-S3-GP"
			(at -5.8039 -0.0889 90)
			(unlocked yes)
			(layer "F.Fab")
			(hide yes)
			(effects
				(font
					(size 1.016 1.016)
					(thickness 0.1524)
				)
			)
		)
		(property "Device Type" "21S-H91-03GB31"
			(at -5.8039 -1.6129 90)
			(unlocked yes)
			(layer "F.Fab")
			(hide yes)
			(effects
				(font
					(size 1.016 1.016)
					(thickness 0.1524)
				)
			)
		)
		(duplicate_pad_numbers_are_jumpers no)
		(fp_line
			(start -4.064 -1.6256)
			(end -2.794 -1.6256)
			(stroke
				(width 0.4064)
				(type default)
			)
			(layer "F.SilkS")
		)
		(fp_line
			(start 3.937 -1.4986)
			(end -3.937 -1.4986)
			(stroke
				(width 0.1524)
				(type default)
			)
			(layer "F.SilkS")
		)
		(fp_line
			(start -3.937 -1.4986)
			(end -3.937 1.4986)
			(stroke
				(width 0.1524)
				(type default)
			)
			(layer "F.SilkS")
		)
		(fp_line
			(start -4.064 -0.3556)
			(end -4.064 -1.6256)
			(stroke
				(width 0.4064)
				(type default)
			)
			(layer "F.SilkS")
		)
		(fp_line
			(start 3.937 1.4986)
			(end 3.937 -1.4986)
			(stroke
				(width 0.1524)
				(type default)
			)
			(layer "F.SilkS")
		)
		(fp_line
			(start -3.937 1.4986)
			(end 3.937 1.4986)
			(stroke
				(width 0.1524)
				(type default)
			)
			(layer "F.SilkS")
		)
		(fp_circle
			(center 2.54 0)
			(end 2.54 1.0668)
			(stroke
				(width 0.3048)
				(type default)
			)
			(fill no)
			(layer "F.SilkS")
		)
		(fp_circle
			(center 0 0)
			(end 0 1.0668)
			(stroke
				(width 0.3048)
				(type default)
			)
			(fill no)
			(layer "F.SilkS")
		)
		(fp_circle
			(center -2.54 0)
			(end -2.54 1.0668)
			(stroke
				(width 0.3048)
				(type default)
			)
			(fill no)
			(layer "F.SilkS")
		)
		(fp_rect
			(start -3.683 1.2446)
			(end 3.683 -1.2446)
			(stroke
				(width 0)
				(type default)
			)
			(fill no)
			(layer "F.CrtYd")
		)
		(fp_poly
			(pts
				(xy 4.191 -1.2446) (xy -3.683 -1.2446) (xy -3.683 1.2446) (xy 3.683 1.2446) (xy 3.683 -1.2319) (xy 4.191 -1.2319)
				(xy 4.191 1.7526) (xy -4.191 1.7526) (xy -4.191 -1.7526) (xy 4.191 -1.7526)
			)
			(stroke
				(width 0)
				(type default)
			)
			(fill no)
			(layer "F.CrtYd")
		)
		(fp_rect
			(start -4.191 1.7526)
			(end 4.191 -1.7526)
			(stroke
				(width 0)
				(type default)
			)
			(fill no)
			(layer "F.Fab")
		)
		(pad "1" thru_hole circle
			(at -2.54 0 90)
			(size 1.4224 1.4224)
			(drill 1.016)
			(layers "*.Cu" "*.Mask")
			(remove_unused_layers no)
			(net "TEMP_ALM#_JP_1")
			(clearance 0.1524)
			(thermal_gap 0.1524)
		)
		(pad "2" thru_hole circle
			(at 0 0 90)
			(size 1.4224 1.4224)
			(drill 1.016)
			(layers "*.Cu" "*.Mask")
			(remove_unused_layers no)
			(net "TEMP_ALM#_JP_2")
			(clearance 0.1524)
			(thermal_gap 0.1524)
		)
		(pad "3" thru_hole circle
			(at 2.54 0 90)
			(size 1.4224 1.4224)
			(drill 1.016)
			(layers "*.Cu" "*.Mask")
			(remove_unused_layers no)
			(net "OTP_RETRY_B")
			(clearance 0.1524)
			(thermal_gap 0.1524)
		)
	)
	(footprint ""
		(layer "F.Cu")
		(at 14.7574 -262.2804 180)
		(property "Reference" "C35"
			(at 0 0 180)
			(layer "F.SilkS")
			(hide yes)
			(effects
				(font
					(size 1.27 1.27)
				)
			)
		)
		(property "Value" "SCD1U16V2KX-3GP"
			(at 1.1811 -2.7051 180)
			(unlocked yes)
			(layer "F.Fab")
			(hide yes)
			(effects
				(font
					(size 1.016 1.016)
					(thickness 0.1524)
				)
			)
		)
		(property "Device Type" "C402H22"
			(at 1.1811 -4.2291 180)
			(unlocked yes)
			(layer "F.Fab")
			(hide yes)
			(effects
				(font
					(size 1.016 1.016)
					(thickness 0.1524)
				)
			)
		)
		(duplicate_pad_numbers_are_jumpers no)
		(fp_rect
			(start -0.4318 0.9525)
			(end 0.4318 -0.9525)
			(stroke
				(width 0)
				(type default)
			)
			(fill no)
			(layer "F.CrtYd")
		)
		(fp_rect
			(start -0.4318 0.9525)
			(end 0.4318 -0.9525)
			(stroke
				(width 0)
				(type default)
			)
			(fill no)
			(layer "F.Fab")
		)
		(pad "1" smd custom
			(at 0 -0.4445 180)
			(size 0.1524 0.1524)
			(layers "F.Cu" "F.Mask" "F.Paste")
			(net "FAN_TACH6")
			(options
				(clearance outline)
				(anchor circle)
			)
			(primitives
				(gr_poly
					(pts
						(arc
							(start 0.3048 -0.2032)
							(mid 0.275042 -0.275042)
							(end 0.2032 -0.3048)
						)
						(arc
							(start -0.2032 -0.3048)
							(mid -0.275042 -0.275042)
							(end -0.3048 -0.2032)
						)
						(arc
							(start -0.3048 0.2032)
							(mid -0.275042 0.275042)
							(end -0.2032 0.3048)
						)
						(arc
							(start 0.2032 0.3048)
							(mid 0.275042 0.275042)
							(end 0.3048 0.2032)
						)
					)
					(width 0)
					(fill yes)
				)
			)
		)
		(pad "2" smd custom
			(at 0 0.4445 180)
			(size 0.1524 0.1524)
			(layers "F.Cu" "F.Mask" "F.Paste")
			(net "GND")
			(options
				(clearance outline)
				(anchor circle)
			)
			(primitives
				(gr_poly
					(pts
						(arc
							(start 0.3048 -0.2032)
							(mid 0.275042 -0.275042)
							(end 0.2032 -0.3048)
						)
						(arc
							(start -0.2032 -0.3048)
							(mid -0.275042 -0.275042)
							(end -0.3048 -0.2032)
						)
						(arc
							(start -0.3048 0.2032)
							(mid -0.275042 0.275042)
							(end -0.2032 0.3048)
						)
						(arc
							(start 0.2032 0.3048)
							(mid 0.275042 0.275042)
							(end 0.3048 0.2032)
						)
					)
					(width 0)
					(fill yes)
				)
			)
		)
	)
	(footprint ""
		(layer "F.Cu")
		(at 20.7264 -26.162 90)
		(property "Reference" "R182"
			(at 0 0 90)
			(layer "F.SilkS")
			(hide yes)
			(effects
				(font
					(size 1.27 1.27)
				)
			)
		)
		(property "Value" "0R1206-PAD-1-GP"
			(at 0 -5.0292 90)
			(unlocked yes)
			(layer "F.Fab")
			(hide yes)
			(effects
				(font
					(size 1.016 1.016)
					(thickness 0.1524)
				)
			)
		)
		(property "Device Type" "0R1206-PAD-1"
			(at 0 -6.5532 90)
			(unlocked yes)
			(layer "F.Fab")
			(hide yes)
			(effects
				(font
					(size 1.016 1.016)
					(thickness 0.1524)
				)
			)
		)
		(duplicate_pad_numbers_are_jumpers no)
		(fp_line
			(start 1.016 -2.2352)
			(end -1.016 -2.2352)
			(stroke
				(width 0.1524)
				(type default)
			)
			(layer "F.SilkS")
		)
		(fp_line
			(start -1.016 -2.2352)
			(end -1.016 2.2352)
			(stroke
				(width 0.1524)
				(type default)
			)
			(layer "F.SilkS")
		)
		(fp_line
			(start 1.016 2.2352)
			(end 1.016 -2.2352)
			(stroke
				(width 0.1524)
				(type default)
			)
			(layer "F.SilkS")
		)
		(fp_line
			(start -1.016 2.2352)
			(end 1.016 2.2352)
			(stroke
				(width 0.1524)
				(type default)
			)
			(layer "F.SilkS")
		)
		(fp_rect
			(start -1.0922 2.3114)
			(end 1.0922 -2.3114)
			(stroke
				(width 0)
				(type default)
			)
			(fill no)
			(layer "F.CrtYd")
		)
		(fp_poly
			(pts
				(xy -1.0922 -2.3114) (xy 1.0922 -2.3114) (xy 1.0922 2.3114) (xy -1.0922 2.3114)
			)
			(stroke
				(width 0)
				(type default)
			)
			(fill no)
			(layer "F.Fab")
		)
		(pad "1" smd rect
			(at 0 -1.397 90)
			(size 1.651 2.0574)
			(drill
				(offset 0 0.3937)
			)
			(layers "F.Cu" "F.Mask" "F.Paste")
			(net "P12V_FAN6")
		)
		(pad "2" smd rect
			(at 0 1.397 90)
			(size 1.651 2.0574)
			(drill
				(offset 0 -0.3937)
			)
			(layers "F.Cu" "F.Mask" "F.Paste")
			(net "P12V")
		)
	)
	(footprint ""
		(layer "F.Cu")
		(at 37.719 -111.633)
		(property "Reference" "PQ8"
			(at 0 0 0)
			(layer "F.SilkS")
			(hide yes)
			(effects
				(font
					(size 1.27 1.27)
				)
			)
		)
		(property "Value" "PH0925CL-GP"
			(at -4.2799 -0.4572 0)
			(unlocked yes)
			(layer "F.Fab")
			(hide yes)
			(effects
				(font
					(size 1.016 1.016)
					(thickness 0.1524)
				)
			)
		)
		(property "Device Type" "LFPAK-5PH48-U"
			(at -4.2799 -1.9812 0)
			(unlocked yes)
			(layer "F.Fab")
			(hide yes)
			(effects
				(font
					(size 1.016 1.016)
					(thickness 0.1524)
				)
			)
		)
		(duplicate_pad_numbers_are_jumpers no)
		(fp_line
			(start -2.7559 -6.5532)
			(end -2.7559 1.0668)
			(stroke
				(width 0.1524)
				(type default)
			)
			(layer "F.SilkS")
		)
		(fp_line
			(start -2.7559 1.0668)
			(end 2.7559 1.0668)
			(stroke
				(width 0.1524)
				(type default)
			)
			(layer "F.SilkS")
		)
		(fp_line
			(start -1.7272 1.1684)
			(end -2.1082 1.1684)
			(stroke
				(width 0.3302)
				(type default)
			)
			(layer "F.SilkS")
		)
		(fp_line
			(start 2.7559 -6.5532)
			(end -2.7559 -6.5532)
			(stroke
				(width 0.1524)
				(type default)
			)
			(layer "F.SilkS")
		)
		(fp_line
			(start 2.7559 1.0668)
			(end 2.7559 -6.5532)
			(stroke
				(width 0.1524)
				(type default)
			)
			(layer "F.SilkS")
		)
		(fp_poly
			(pts
				(xy -2.3368 1.5748) (xy -1.905 1.143) (xy -1.4732 1.5748)
			)
			(stroke
				(width 0)
				(type default)
			)
			(fill yes)
			(layer "F.SilkS")
		)
		(fp_poly
			(pts
				(xy -2.5019 -4.02971) (xy -0.3302 -4.02971) (xy -0.3302 -6.30301) (xy -2.5019 -6.30301)
			)
			(stroke
				(width 0)
				(type default)
			)
			(fill yes)
			(layer "F.Paste")
		)
		(fp_poly
			(pts
				(xy -2.5019 -1.09601) (xy -0.3302 -1.09601) (xy -0.3302 -3.36931) (xy -2.5019 -3.36931)
			)
			(stroke
				(width 0)
				(type default)
			)
			(fill yes)
			(layer "F.Paste")
		)
		(fp_poly
			(pts
				(xy 0.3302 -4.02971) (xy 2.5019 -4.02971) (xy 2.5019 -6.30301) (xy 0.3302 -6.30301)
			)
			(stroke
				(width 0)
				(type default)
			)
			(fill yes)
			(layer "F.Paste")
		)
		(fp_poly
			(pts
				(xy 0.3302 -1.09601) (xy 2.5019 -1.09601) (xy 2.5019 -3.36931) (xy 0.3302 -3.36931)
			)
			(stroke
				(width 0)
				(type default)
			)
			(fill yes)
			(layer "F.Paste")
		)
		(fp_rect
			(start -2.4511 0.3048)
			(end 2.4511 -5.6896)
			(stroke
				(width 0)
				(type default)
			)
			(fill no)
			(layer "F.CrtYd")
		)
		(fp_poly
			(pts
				(xy -3.0099 1.3208) (xy -3.0099 -6.8072) (xy 3.0099 -6.8072) (xy 3.0099 -1.016) (xy 2.4511 -1.016)
				(xy 2.4511 -5.6896) (xy -2.4511 -5.6896) (xy -2.4511 0.3048) (xy 2.4511 0.3048) (xy 2.4511 -1.0033)
				(xy 3.0099 -1.0033) (xy 3.0099 1.3208)
			)
			(stroke
				(width 0)
				(type default)
			)
			(fill no)
			(layer "F.CrtYd")
		)
		(fp_rect
			(start -3.0099 1.3208)
			(end 3.0099 -6.8072)
			(stroke
				(width 0)
				(type default)
			)
			(fill no)
			(layer "F.Fab")
		)
		(pad "1" smd rect
			(at -1.905 0)
			(size 0.762 1.6256)
			(layers "F.Cu" "F.Mask" "F.Paste")
			(net "P12VL")
		)
		(pad "2" smd rect
			(at -0.635 0)
			(size 0.762 1.6256)
			(layers "F.Cu" "F.Mask" "F.Paste")
			(net "P12VL")
		)
		(pad "3" smd rect
			(at 0.635 0)
			(size 0.762 1.6256)
			(layers "F.Cu" "F.Mask" "F.Paste")
			(net "P12VL")
		)
		(pad "4" smd rect
			(at 1.905 0)
			(size 0.762 1.6256)
			(layers "F.Cu" "F.Mask" "F.Paste")
			(net "P12VL_2490_GATE_DRV")
		)
		(pad "5" smd rect
			(at 0 -3.69951)
			(size 5.0038 5.207)
			(layers "F.Cu" "F.Mask" "F.Paste")
			(net "P12VL_NET")
		)
	)
)
